(kicad_pcb
	(version 20260206)
	(generator "pcbnew")
	(generator_version "10.0")
	(general
		(thickness 1.6)
		(legacy_teardrops no)
	)
	(paper "A4")
	(title_block
		(title "04192023_DAF0TMB3IC0_F0TG_MB_C_brd_V02_OCP.brd")
		(comment 1 "Grand Teton / footprints 3476-3481 of 8354")
	)
	(layers
		(0 "F.Cu" signal "TOP")
		(4 "In1.Cu" signal "GND")
		(6 "In2.Cu" signal "IN1")
		(8 "In3.Cu" signal "GND1")
		(10 "In4.Cu" signal "IN2")
		(12 "In5.Cu" signal "GND2")
		(14 "In6.Cu" signal "IN3")
		(16 "In7.Cu" signal "GND3")
		(18 "In8.Cu" signal "VCC")
		(20 "In9.Cu" signal "VCC1")
		(22 "In10.Cu" signal "GND4")
		(24 "In11.Cu" signal "IN4")
		(26 "In12.Cu" signal "GND5")
		(28 "In13.Cu" signal "IN5")
		(30 "In14.Cu" signal "GND6")
		(32 "In15.Cu" signal "IN6")
		(34 "In16.Cu" signal "GND7")
		(2 "B.Cu" signal "BOTTOM")
		(9 "F.Adhes" user "F.Adhesive")
		(11 "B.Adhes" user "B.Adhesive")
		(13 "F.Paste" user "Package Geometry/Pastemask Top")
		(15 "B.Paste" user "Package Geometry/Pastemask Bottom")
		(5 "F.SilkS" user "Ref Des/Silkscreen Top")
		(7 "B.SilkS" user "Ref Des/Silkscreen Bottom")
		(1 "F.Mask" user "Board Geometry/Soldermask Top")
		(3 "B.Mask" user "Board Geometry/Soldermask Bottom")
		(17 "Dwgs.User" user "User.Drawings")
		(19 "Cmts.User" user "User.Comments")
		(21 "Eco1.User" user "User.Eco1")
		(23 "Eco2.User" user "User.Eco2")
		(25 "Edge.Cuts" user "Board Geometry/Outline")
		(27 "Margin" user)
		(31 "F.CrtYd" user "Package Geometry/Place Bound Top")
		(29 "B.CrtYd" user "Package Geometry/Place Bound Bottom")
		(35 "F.Fab" user "Ref Des/Assembly Top")
		(33 "B.Fab" user "Ref Des/Assembly Bottom")
	)
	(footprint ""
		(layer "F.Cu")
		(at 36.195 -360.045 180)
		(property "Reference" "PC361"
			(at 0 0 180)
			(layer "F.SilkS")
			(hide yes)
			(effects
				(font
					(size 1.27 1.27)
				)
			)
		)
		(property "Value" ""
			(at 0 0 180)
			(layer "F.Fab")
			(effects
				(font
					(size 1.27 1.27)
				)
			)
		)
		(duplicate_pad_numbers_are_jumpers no)
		(fp_line
			(start 0.7874 0.4064)
			(end -0.7874 0.4064)
			(stroke
				(width 0.1524)
				(type default)
			)
			(layer "F.SilkS")
		)
		(fp_line
			(start 0.7874 -0.4064)
			(end 0.7874 0.4064)
			(stroke
				(width 0.1524)
				(type default)
			)
			(layer "F.SilkS")
		)
		(fp_line
			(start -0.7874 0.4064)
			(end -0.7874 -0.4064)
			(stroke
				(width 0.1524)
				(type default)
			)
			(layer "F.SilkS")
		)
		(fp_line
			(start -0.7874 -0.4064)
			(end 0.7874 -0.4064)
			(stroke
				(width 0.1524)
				(type default)
			)
			(layer "F.SilkS")
		)
		(fp_line
			(start 0.67945 0.3048)
			(end 0.120396 0.3048)
			(stroke
				(width 0.1)
				(type default)
			)
			(layer "F.Fab")
		)
		(fp_line
			(start 0.67945 -0.3048)
			(end 0.67945 0.3048)
			(stroke
				(width 0.1)
				(type default)
			)
			(layer "F.Fab")
		)
		(fp_line
			(start 0.12065 -0.2794)
			(end 0.12065 -0.3048)
			(stroke
				(width 0.1)
				(type default)
			)
			(layer "F.Fab")
		)
		(fp_line
			(start 0.12065 -0.3048)
			(end 0.67945 -0.3048)
			(stroke
				(width 0.1)
				(type default)
			)
			(layer "F.Fab")
		)
		(fp_line
			(start 0.120396 0.3048)
			(end 0.120396 0.2794)
			(stroke
				(width 0.1)
				(type default)
			)
			(layer "F.Fab")
		)
		(fp_line
			(start 0.120396 0.2794)
			(end -0.12065 0.2794)
			(stroke
				(width 0.1)
				(type default)
			)
			(layer "F.Fab")
		)
		(fp_line
			(start -0.12065 0.3048)
			(end -0.67945 0.3048)
			(stroke
				(width 0.1)
				(type default)
			)
			(layer "F.Fab")
		)
		(fp_line
			(start -0.12065 0.2794)
			(end -0.12065 0.3048)
			(stroke
				(width 0.1)
				(type default)
			)
			(layer "F.Fab")
		)
		(fp_line
			(start -0.12065 -0.2794)
			(end 0.12065 -0.2794)
			(stroke
				(width 0.1)
				(type default)
			)
			(layer "F.Fab")
		)
		(fp_line
			(start -0.12065 -0.305054)
			(end -0.12065 -0.2794)
			(stroke
				(width 0.1)
				(type default)
			)
			(layer "F.Fab")
		)
		(fp_line
			(start -0.67945 0.3048)
			(end -0.67945 -0.305054)
			(stroke
				(width 0.1)
				(type default)
			)
			(layer "F.Fab")
		)
		(fp_line
			(start -0.67945 -0.305054)
			(end -0.12065 -0.305054)
			(stroke
				(width 0.1)
				(type default)
			)
			(layer "F.Fab")
		)
		(pad "1" smd circle
			(at -0.40005 0 180)
			(size 0 0)
			(layers "F.Cu" "F.Mask" "F.Paste")
			(net "VSENSE_PVDDIO_P1_VSEN1")
		)
		(pad "2" smd circle
			(at 0.40005 0 180)
			(size 0 0)
			(layers "F.Cu" "F.Mask" "F.Paste")
			(net "VSENSE_VSS_SENSE_B_P1")
		)
	)
	(footprint ""
		(layer "F.Cu")
		(at 117.792754 -76.987654 90)
		(property "Reference" "PC6013"
			(at 0 0 90)
			(layer "F.SilkS")
			(hide yes)
			(effects
				(font
					(size 1.27 1.27)
				)
			)
		)
		(property "Value" ""
			(at 0 0 90)
			(layer "F.Fab")
			(effects
				(font
					(size 1.27 1.27)
				)
			)
		)
		(duplicate_pad_numbers_are_jumpers no)
		(fp_line
			(start 1.524 -0.762)
			(end 1.524 0.762)
			(stroke
				(width 0.1524)
				(type default)
			)
			(layer "F.SilkS")
		)
		(fp_line
			(start -1.524 -0.762)
			(end 1.524 -0.762)
			(stroke
				(width 0.1524)
				(type default)
			)
			(layer "F.SilkS")
		)
		(fp_line
			(start 1.524 0.762)
			(end -1.524 0.762)
			(stroke
				(width 0.1524)
				(type default)
			)
			(layer "F.SilkS")
		)
		(fp_line
			(start -1.524 0.762)
			(end -1.524 -0.762)
			(stroke
				(width 0.1524)
				(type default)
			)
			(layer "F.SilkS")
		)
		(fp_line
			(start 1.1049 -0.724916)
			(end -1.1049 -0.724916)
			(stroke
				(width 0.1)
				(type default)
			)
			(layer "F.Fab")
		)
		(fp_line
			(start -1.1049 -0.724916)
			(end -1.1049 0.724916)
			(stroke
				(width 0.1)
				(type default)
			)
			(layer "F.Fab")
		)
		(fp_line
			(start 1.1049 0.724916)
			(end 1.1049 -0.724916)
			(stroke
				(width 0.1)
				(type default)
			)
			(layer "F.Fab")
		)
		(fp_line
			(start -1.1049 0.724916)
			(end 1.1049 0.724916)
			(stroke
				(width 0.1)
				(type default)
			)
			(layer "F.Fab")
		)
		(pad "1" smd rect
			(at -0.889 0 270)
			(size 1.016 1.27)
			(layers "F.Cu" "F.Mask" "F.Paste")
			(net "SW_P12V_AUX_P1V2_AUX_FLT")
		)
		(pad "2" smd rect
			(at 0.889 0 270)
			(size 1.016 1.27)
			(layers "F.Cu" "F.Mask" "F.Paste")
			(net "GND")
		)
	)
	(footprint ""
		(layer "F.Cu")
		(at 159.07893 -352.668078 -90)
		(property "Reference" "R8383"
			(at 0 0 270)
			(layer "F.SilkS")
			(hide yes)
			(effects
				(font
					(size 1.27 1.27)
				)
			)
		)
		(property "Value" ""
			(at 0 0 270)
			(layer "F.Fab")
			(effects
				(font
					(size 1.27 1.27)
				)
			)
		)
		(duplicate_pad_numbers_are_jumpers no)
		(fp_line
			(start -0.7874 0.4064)
			(end -0.7874 -0.4064)
			(stroke
				(width 0.1524)
				(type default)
			)
			(layer "F.SilkS")
		)
		(fp_line
			(start 0.7874 0.4064)
			(end -0.7874 0.4064)
			(stroke
				(width 0.1524)
				(type default)
			)
			(layer "F.SilkS")
		)
		(fp_line
			(start -0.7874 -0.4064)
			(end 0.7874 -0.4064)
			(stroke
				(width 0.1524)
				(type default)
			)
			(layer "F.SilkS")
		)
		(fp_line
			(start 0.7874 -0.4064)
			(end 0.7874 0.4064)
			(stroke
				(width 0.1524)
				(type default)
			)
			(layer "F.SilkS")
		)
		(fp_line
			(start -0.67945 0.3048)
			(end -0.67945 -0.305054)
			(stroke
				(width 0.1)
				(type default)
			)
			(layer "F.Fab")
		)
		(fp_line
			(start -0.12065 0.3048)
			(end -0.67945 0.3048)
			(stroke
				(width 0.1)
				(type default)
			)
			(layer "F.Fab")
		)
		(fp_line
			(start 0.120396 0.3048)
			(end 0.120396 0.2794)
			(stroke
				(width 0.1)
				(type default)
			)
			(layer "F.Fab")
		)
		(fp_line
			(start 0.67945 0.3048)
			(end 0.120396 0.3048)
			(stroke
				(width 0.1)
				(type default)
			)
			(layer "F.Fab")
		)
		(fp_line
			(start -0.12065 0.2794)
			(end -0.12065 0.3048)
			(stroke
				(width 0.1)
				(type default)
			)
			(layer "F.Fab")
		)
		(fp_line
			(start 0.120396 0.2794)
			(end -0.12065 0.2794)
			(stroke
				(width 0.1)
				(type default)
			)
			(layer "F.Fab")
		)
		(fp_line
			(start -0.12065 -0.2794)
			(end 0.12065 -0.2794)
			(stroke
				(width 0.1)
				(type default)
			)
			(layer "F.Fab")
		)
		(fp_line
			(start 0.12065 -0.2794)
			(end 0.12065 -0.3048)
			(stroke
				(width 0.1)
				(type default)
			)
			(layer "F.Fab")
		)
		(fp_line
			(start 0.12065 -0.3048)
			(end 0.67945 -0.3048)
			(stroke
				(width 0.1)
				(type default)
			)
			(layer "F.Fab")
		)
		(fp_line
			(start 0.67945 -0.3048)
			(end 0.67945 0.3048)
			(stroke
				(width 0.1)
				(type default)
			)
			(layer "F.Fab")
		)
		(fp_line
			(start -0.67945 -0.305054)
			(end -0.12065 -0.305054)
			(stroke
				(width 0.1)
				(type default)
			)
			(layer "F.Fab")
		)
		(fp_line
			(start -0.12065 -0.305054)
			(end -0.12065 -0.2794)
			(stroke
				(width 0.1)
				(type default)
			)
			(layer "F.Fab")
		)
		(pad "1" smd circle
			(at -0.40005 0 270)
			(size 0 0)
			(layers "F.Cu" "F.Mask" "F.Paste")
			(net "PVDD11_S3_P1_PMALERT")
		)
		(pad "2" smd circle
			(at 0.40005 0 270)
			(size 0 0)
			(layers "F.Cu" "F.Mask" "F.Paste")
			(net "PVDD11_S3_P1_PMALERT_R")
		)
	)
	(footprint ""
		(layer "F.Cu")
		(at 305.175158 -439.877962 180)
		(property "Reference" "R4138"
			(at 0 0 180)
			(layer "F.SilkS")
			(hide yes)
			(effects
				(font
					(size 1.27 1.27)
				)
			)
		)
		(property "Value" ""
			(at 0 0 180)
			(layer "F.Fab")
			(effects
				(font
					(size 1.27 1.27)
				)
			)
		)
		(duplicate_pad_numbers_are_jumpers no)
		(fp_line
			(start 0.7874 0.4064)
			(end -0.7874 0.4064)
			(stroke
				(width 0.1524)
				(type default)
			)
			(layer "F.SilkS")
		)
		(fp_line
			(start 0.7874 -0.4064)
			(end 0.7874 0.4064)
			(stroke
				(width 0.1524)
				(type default)
			)
			(layer "F.SilkS")
		)
		(fp_line
			(start -0.7874 0.4064)
			(end -0.7874 -0.4064)
			(stroke
				(width 0.1524)
				(type default)
			)
			(layer "F.SilkS")
		)
		(fp_line
			(start -0.7874 -0.4064)
			(end 0.7874 -0.4064)
			(stroke
				(width 0.1524)
				(type default)
			)
			(layer "F.SilkS")
		)
		(fp_line
			(start 0.67945 0.3048)
			(end 0.120396 0.3048)
			(stroke
				(width 0.1)
				(type default)
			)
			(layer "F.Fab")
		)
		(fp_line
			(start 0.67945 -0.3048)
			(end 0.67945 0.3048)
			(stroke
				(width 0.1)
				(type default)
			)
			(layer "F.Fab")
		)
		(fp_line
			(start 0.12065 -0.2794)
			(end 0.12065 -0.3048)
			(stroke
				(width 0.1)
				(type default)
			)
			(layer "F.Fab")
		)
		(fp_line
			(start 0.12065 -0.3048)
			(end 0.67945 -0.3048)
			(stroke
				(width 0.1)
				(type default)
			)
			(layer "F.Fab")
		)
		(fp_line
			(start 0.120396 0.3048)
			(end 0.120396 0.2794)
			(stroke
				(width 0.1)
				(type default)
			)
			(layer "F.Fab")
		)
		(fp_line
			(start 0.120396 0.2794)
			(end -0.12065 0.2794)
			(stroke
				(width 0.1)
				(type default)
			)
			(layer "F.Fab")
		)
		(fp_line
			(start -0.12065 0.3048)
			(end -0.67945 0.3048)
			(stroke
				(width 0.1)
				(type default)
			)
			(layer "F.Fab")
		)
		(fp_line
			(start -0.12065 0.2794)
			(end -0.12065 0.3048)
			(stroke
				(width 0.1)
				(type default)
			)
			(layer "F.Fab")
		)
		(fp_line
			(start -0.12065 -0.2794)
			(end 0.12065 -0.2794)
			(stroke
				(width 0.1)
				(type default)
			)
			(layer "F.Fab")
		)
		(fp_line
			(start -0.12065 -0.305054)
			(end -0.12065 -0.2794)
			(stroke
				(width 0.1)
				(type default)
			)
			(layer "F.Fab")
		)
		(fp_line
			(start -0.67945 0.3048)
			(end -0.67945 -0.305054)
			(stroke
				(width 0.1)
				(type default)
			)
			(layer "F.Fab")
		)
		(fp_line
			(start -0.67945 -0.305054)
			(end -0.12065 -0.305054)
			(stroke
				(width 0.1)
				(type default)
			)
			(layer "F.Fab")
		)
		(pad "1" smd circle
			(at -0.40005 0 180)
			(size 0 0)
			(layers "F.Cu" "F.Mask" "F.Paste")
			(net "P3V3_AUX")
		)
		(pad "2" smd circle
			(at 0.40005 0 180)
			(size 0 0)
			(layers "F.Cu" "F.Mask" "F.Paste")
			(net "GPU_3V3IO_RSVD5_FFU_N")
		)
	)
	(footprint ""
		(layer "F.Cu")
		(at 177.927 -137.632948 90)
		(property "Reference" "R18"
			(at 0 0 90)
			(layer "F.SilkS")
			(hide yes)
			(effects
				(font
					(size 1.27 1.27)
				)
			)
		)
		(property "Value" ""
			(at 0 0 90)
			(layer "F.Fab")
			(effects
				(font
					(size 1.27 1.27)
				)
			)
		)
		(duplicate_pad_numbers_are_jumpers no)
		(fp_line
			(start 0.7874 -0.4064)
			(end 0.7874 0.4064)
			(stroke
				(width 0.1524)
				(type default)
			)
			(layer "F.SilkS")
		)
		(fp_line
			(start -0.7874 -0.4064)
			(end 0.7874 -0.4064)
			(stroke
				(width 0.1524)
				(type default)
			)
			(layer "F.SilkS")
		)
		(fp_line
			(start 0.7874 0.4064)
			(end -0.7874 0.4064)
			(stroke
				(width 0.1524)
				(type default)
			)
			(layer "F.SilkS")
		)
		(fp_line
			(start -0.7874 0.4064)
			(end -0.7874 -0.4064)
			(stroke
				(width 0.1524)
				(type default)
			)
			(layer "F.SilkS")
		)
		(fp_line
			(start -0.12065 -0.305054)
			(end -0.12065 -0.2794)
			(stroke
				(width 0.1)
				(type default)
			)
			(layer "F.Fab")
		)
		(fp_line
			(start -0.67945 -0.305054)
			(end -0.12065 -0.305054)
			(stroke
				(width 0.1)
				(type default)
			)
			(layer "F.Fab")
		)
		(fp_line
			(start 0.67945 -0.3048)
			(end 0.67945 0.3048)
			(stroke
				(width 0.1)
				(type default)
			)
			(layer "F.Fab")
		)
		(fp_line
			(start 0.12065 -0.3048)
			(end 0.67945 -0.3048)
			(stroke
				(width 0.1)
				(type default)
			)
			(layer "F.Fab")
		)
		(fp_line
			(start 0.12065 -0.2794)
			(end 0.12065 -0.3048)
			(stroke
				(width 0.1)
				(type default)
			)
			(layer "F.Fab")
		)
		(fp_line
			(start -0.12065 -0.2794)
			(end 0.12065 -0.2794)
			(stroke
				(width 0.1)
				(type default)
			)
			(layer "F.Fab")
		)
		(fp_line
			(start 0.120396 0.2794)
			(end -0.12065 0.2794)
			(stroke
				(width 0.1)
				(type default)
			)
			(layer "F.Fab")
		)
		(fp_line
			(start -0.12065 0.2794)
			(end -0.12065 0.3048)
			(stroke
				(width 0.1)
				(type default)
			)
			(layer "F.Fab")
		)
		(fp_line
			(start 0.67945 0.3048)
			(end 0.120396 0.3048)
			(stroke
				(width 0.1)
				(type default)
			)
			(layer "F.Fab")
		)
		(fp_line
			(start 0.120396 0.3048)
			(end 0.120396 0.2794)
			(stroke
				(width 0.1)
				(type default)
			)
			(layer "F.Fab")
		)
		(fp_line
			(start -0.12065 0.3048)
			(end -0.67945 0.3048)
			(stroke
				(width 0.1)
				(type default)
			)
			(layer "F.Fab")
		)
		(fp_line
			(start -0.67945 0.3048)
			(end -0.67945 -0.305054)
			(stroke
				(width 0.1)
				(type default)
			)
			(layer "F.Fab")
		)
		(pad "1" smd circle
			(at -0.40005 0 90)
			(size 0 0)
			(layers "F.Cu" "F.Mask" "F.Paste")
			(net "RST_CPU1_PERST0_N")
		)
		(pad "2" smd circle
			(at 0.40005 0 90)
			(size 0 0)
			(layers "F.Cu" "F.Mask" "F.Paste")
			(net "GND")
		)
	)
	(footprint ""
		(layer "F.Cu")
		(at 416.136836 -142.185898 -90)
		(property "Reference" "PC1848"
			(at 0 0 270)
			(layer "F.SilkS")
			(hide yes)
			(effects
				(font
					(size 1.27 1.27)
				)
			)
		)
		(property "Value" ""
			(at 0 0 270)
			(layer "F.Fab")
			(effects
				(font
					(size 1.27 1.27)
				)
			)
		)
		(duplicate_pad_numbers_are_jumpers no)
		(fp_line
			(start -0.7874 0.4064)
			(end -0.7874 -0.4064)
			(stroke
				(width 0.1524)
				(type default)
			)
			(layer "F.SilkS")
		)
		(fp_line
			(start 0.7874 0.4064)
			(end -0.7874 0.4064)
			(stroke
				(width 0.1524)
				(type default)
			)
			(layer "F.SilkS")
		)
		(fp_line
			(start -0.7874 -0.4064)
			(end 0.7874 -0.4064)
			(stroke
				(width 0.1524)
				(type default)
			)
			(layer "F.SilkS")
		)
		(fp_line
			(start 0.7874 -0.4064)
			(end 0.7874 0.4064)
			(stroke
				(width 0.1524)
				(type default)
			)
			(layer "F.SilkS")
		)
		(fp_line
			(start -0.67945 0.3048)
			(end -0.67945 -0.305054)
			(stroke
				(width 0.1)
				(type default)
			)
			(layer "F.Fab")
		)
		(fp_line
			(start -0.12065 0.3048)
			(end -0.67945 0.3048)
			(stroke
				(width 0.1)
				(type default)
			)
			(layer "F.Fab")
		)
		(fp_line
			(start 0.120396 0.3048)
			(end 0.120396 0.2794)
			(stroke
				(width 0.1)
				(type default)
			)
			(layer "F.Fab")
		)
		(fp_line
			(start 0.67945 0.3048)
			(end 0.120396 0.3048)
			(stroke
				(width 0.1)
				(type default)
			)
			(layer "F.Fab")
		)
		(fp_line
			(start -0.12065 0.2794)
			(end -0.12065 0.3048)
			(stroke
				(width 0.1)
				(type default)
			)
			(layer "F.Fab")
		)
		(fp_line
			(start 0.120396 0.2794)
			(end -0.12065 0.2794)
			(stroke
				(width 0.1)
				(type default)
			)
			(layer "F.Fab")
		)
		(fp_line
			(start -0.12065 -0.2794)
			(end 0.12065 -0.2794)
			(stroke
				(width 0.1)
				(type default)
			)
			(layer "F.Fab")
		)
		(fp_line
			(start 0.12065 -0.2794)
			(end 0.12065 -0.3048)
			(stroke
				(width 0.1)
				(type default)
			)
			(layer "F.Fab")
		)
		(fp_line
			(start 0.12065 -0.3048)
			(end 0.67945 -0.3048)
			(stroke
				(width 0.1)
				(type default)
			)
			(layer "F.Fab")
		)
		(fp_line
			(start 0.67945 -0.3048)
			(end 0.67945 0.3048)
			(stroke
				(width 0.1)
				(type default)
			)
			(layer "F.Fab")
		)
		(fp_line
			(start -0.67945 -0.305054)
			(end -0.12065 -0.305054)
			(stroke
				(width 0.1)
				(type default)
			)
			(layer "F.Fab")
		)
		(fp_line
			(start -0.12065 -0.305054)
			(end -0.12065 -0.2794)
			(stroke
				(width 0.1)
				(type default)
			)
			(layer "F.Fab")
		)
		(pad "1" smd circle
			(at -0.40005 0 270)
			(size 0 0)
			(layers "F.Cu" "F.Mask" "F.Paste")
			(net "P5V_AUX_VCC")
		)
		(pad "2" smd circle
			(at 0.40005 0 270)
			(size 0 0)
			(layers "F.Cu" "F.Mask" "F.Paste")
			(net "GND")
		)
	)
)
